(kicad_pcb
	(version 20260206)
	(generator "pcbnew")
	(generator_version "10.0")
	(general
		(thickness 1.6)
		(legacy_teardrops no)
	)
	(paper "A4")
	(title_block
		(title "baseboard — 13948-1b.1110WZS1818.brd")
		(comment 1 "Honey Badger (Wiwynn) / footprints 1601-1607 of 2523")
	)
	(layers
		(0 "F.Cu" signal "TOP")
		(4 "In1.Cu" signal "L2GND")
		(6 "In2.Cu" signal "L3")
		(8 "In3.Cu" signal "L4VCC")
		(10 "In4.Cu" signal "L5VCC")
		(12 "In5.Cu" signal "L6")
		(14 "In6.Cu" signal "L7GND")
		(2 "B.Cu" signal "BOTTOM")
		(9 "F.Adhes" user "F.Adhesive")
		(11 "B.Adhes" user "B.Adhesive")
		(13 "F.Paste" user "Package Geometry/Pastemask Top")
		(15 "B.Paste" user "Package Geometry/Pastemask Bottom")
		(5 "F.SilkS" user "Ref Des/Silkscreen Top")
		(7 "B.SilkS" user "Ref Des/Silkscreen Bottom")
		(1 "F.Mask" user "Board Geometry/Soldermask Top")
		(3 "B.Mask" user "Board Geometry/Soldermask Bottom")
		(17 "Dwgs.User" user "User.Drawings")
		(19 "Cmts.User" user "User.Comments")
		(21 "Eco1.User" user "User.Eco1")
		(23 "Eco2.User" user "User.Eco2")
		(25 "Edge.Cuts" user "Board Geometry/Outline")
		(27 "Margin" user)
		(31 "F.CrtYd" user "Package Geometry/Place Bound Top")
		(29 "B.CrtYd" user "Package Geometry/Place Bound Bottom")
		(35 "F.Fab" user "Ref Des/Assembly Top")
		(33 "B.Fab" user "Ref Des/Assembly Bottom")
	)
	(footprint ""
		(layer "F.Cu")
		(at 38.989 -172.847 180)
		(property "Reference" "SR1275"
			(at 0 0 180)
			(layer "F.SilkS")
			(hide yes)
			(effects
				(font
					(size 1.27 1.27)
				)
			)
		)
		(property "Value" "10KR2F-2-GP"
			(at 0.064008 -3.993896 180)
			(unlocked yes)
			(layer "F.Fab")
			(hide yes)
			(effects
				(font
					(size 1.016 1.016)
					(thickness 0.1524)
				)
			)
		)
		(property "Device Type" "R402H16"
			(at 0.064008 -5.517896 180)
			(unlocked yes)
			(layer "F.Fab")
			(hide yes)
			(effects
				(font
					(size 1.016 1.016)
					(thickness 0.1524)
				)
			)
		)
		(duplicate_pad_numbers_are_jumpers no)
		(fp_line
			(start 0.508 -0.9398)
			(end -0.508 -0.9398)
			(stroke
				(width 0.1524)
				(type default)
			)
			(layer "F.SilkS")
		)
		(fp_line
			(start -0.508 -0.9398)
			(end -0.508 0.9398)
			(stroke
				(width 0.1524)
				(type default)
			)
			(layer "F.SilkS")
		)
		(fp_rect
			(start -0.508 0.9398)
			(end 0.508 -0.9398)
			(stroke
				(width 0)
				(type default)
			)
			(fill no)
			(layer "F.CrtYd")
		)
		(fp_rect
			(start -0.508 0.9398)
			(end 0.508 -0.9398)
			(stroke
				(width 0)
				(type default)
			)
			(fill no)
			(layer "F.Fab")
		)
		(pad "1" smd custom
			(at 0 -0.4445 180)
			(size 0.1397 0.1397)
			(layers "F.Cu" "F.Mask" "F.Paste")
			(net "P3V3_STBY_R7")
			(options
				(clearance outline)
				(anchor circle)
			)
			(primitives
				(gr_poly
					(pts
						(arc
							(start -0.1778 -0.2794)
							(mid -0.249642 -0.249642)
							(end -0.2794 -0.1778)
						)
						(arc
							(start -0.2794 0.1778)
							(mid -0.249642 0.249642)
							(end -0.1778 0.2794)
						)
						(arc
							(start 0.1778 0.2794)
							(mid 0.249642 0.249642)
							(end 0.2794 0.1778)
						)
						(arc
							(start 0.2794 -0.1778)
							(mid 0.249642 -0.249642)
							(end 0.1778 -0.2794)
						)
					)
					(width 0)
					(fill yes)
				)
			)
		)
		(pad "2" smd custom
			(at 0 0.4445 180)
			(size 0.1397 0.1397)
			(layers "F.Cu" "F.Mask" "F.Paste")
			(net "P3V3_STBY_G7")
			(options
				(clearance outline)
				(anchor circle)
			)
			(primitives
				(gr_poly
					(pts
						(arc
							(start -0.1778 -0.2794)
							(mid -0.249642 -0.249642)
							(end -0.2794 -0.1778)
						)
						(arc
							(start -0.2794 0.1778)
							(mid -0.249642 0.249642)
							(end -0.1778 0.2794)
						)
						(arc
							(start 0.1778 0.2794)
							(mid 0.249642 0.249642)
							(end 0.2794 0.1778)
						)
						(arc
							(start 0.2794 -0.1778)
							(mid 0.249642 -0.249642)
							(end 0.1778 -0.2794)
						)
					)
					(width 0)
					(fill yes)
				)
			)
		)
	)
	(footprint ""
		(layer "F.Cu")
		(at 117.856 -72.771 -90)
		(property "Reference" "R5313"
			(at 0 0 270)
			(layer "F.SilkS")
			(hide yes)
			(effects
				(font
					(size 1.27 1.27)
				)
			)
		)
		(property "Value" "0R2J-2-GP"
			(at 0.064008 -3.993896 270)
			(unlocked yes)
			(layer "F.Fab")
			(hide yes)
			(effects
				(font
					(size 1.016 1.016)
					(thickness 0.1524)
				)
			)
		)
		(property "Device Type" "R402H16"
			(at 0.064008 -5.517896 270)
			(unlocked yes)
			(layer "F.Fab")
			(hide yes)
			(effects
				(font
					(size 1.016 1.016)
					(thickness 0.1524)
				)
			)
		)
		(duplicate_pad_numbers_are_jumpers no)
		(fp_line
			(start -0.508 -0.9398)
			(end -0.508 0.9398)
			(stroke
				(width 0.1524)
				(type default)
			)
			(layer "F.SilkS")
		)
		(fp_line
			(start 0.508 -0.9398)
			(end -0.508 -0.9398)
			(stroke
				(width 0.1524)
				(type default)
			)
			(layer "F.SilkS")
		)
		(fp_rect
			(start -0.508 0.9398)
			(end 0.508 -0.9398)
			(stroke
				(width 0)
				(type default)
			)
			(fill no)
			(layer "F.CrtYd")
		)
		(fp_rect
			(start -0.508 0.9398)
			(end 0.508 -0.9398)
			(stroke
				(width 0)
				(type default)
			)
			(fill no)
			(layer "F.Fab")
		)
		(pad "1" smd custom
			(at 0 -0.4445 270)
			(size 0.1397 0.1397)
			(layers "F.Cu" "F.Mask" "F.Paste")
			(net "BMC_I2C_SCL_10")
			(options
				(clearance outline)
				(anchor circle)
			)
			(primitives
				(gr_poly
					(pts
						(arc
							(start -0.1778 -0.2794)
							(mid -0.249642 -0.249642)
							(end -0.2794 -0.1778)
						)
						(arc
							(start -0.2794 0.1778)
							(mid -0.249642 0.249642)
							(end -0.1778 0.2794)
						)
						(arc
							(start 0.1778 0.2794)
							(mid 0.249642 0.249642)
							(end 0.2794 0.1778)
						)
						(arc
							(start 0.2794 -0.1778)
							(mid 0.249642 -0.249642)
							(end 0.1778 -0.2794)
						)
					)
					(width 0)
					(fill yes)
				)
			)
		)
		(pad "2" smd custom
			(at 0 0.4445 270)
			(size 0.1397 0.1397)
			(layers "F.Cu" "F.Mask" "F.Paste")
			(net "TEMP_4_SCL")
			(options
				(clearance outline)
				(anchor circle)
			)
			(primitives
				(gr_poly
					(pts
						(arc
							(start -0.1778 -0.2794)
							(mid -0.249642 -0.249642)
							(end -0.2794 -0.1778)
						)
						(arc
							(start -0.2794 0.1778)
							(mid -0.249642 0.249642)
							(end -0.1778 0.2794)
						)
						(arc
							(start 0.1778 0.2794)
							(mid 0.249642 0.249642)
							(end 0.2794 0.1778)
						)
						(arc
							(start 0.2794 -0.1778)
							(mid 0.249642 -0.249642)
							(end 0.1778 -0.2794)
						)
					)
					(width 0)
					(fill yes)
				)
			)
		)
	)
	(footprint ""
		(layer "F.Cu")
		(at 265.049 -22.733 -90)
		(property "Reference" "PC59"
			(at 0 0 270)
			(layer "F.SilkS")
			(hide yes)
			(effects
				(font
					(size 1.27 1.27)
				)
			)
		)
		(property "Value" "SC100U6D3V6MX-GP"
			(at -0.0762 -5.1308 270)
			(unlocked yes)
			(layer "F.Fab")
			(hide yes)
			(effects
				(font
					(size 1.016 1.016)
					(thickness 0.1524)
				)
			)
		)
		(property "Device Type" "C1206H71"
			(at -0.127 -6.6548 270)
			(unlocked yes)
			(layer "F.Fab")
			(hide yes)
			(effects
				(font
					(size 1.016 1.016)
					(thickness 0.1524)
				)
			)
		)
		(duplicate_pad_numbers_are_jumpers no)
		(fp_line
			(start -1.016 2.2352)
			(end -1.016 0.8382)
			(stroke
				(width 0.1524)
				(type default)
			)
			(layer "F.SilkS")
		)
		(fp_line
			(start 1.016 2.2352)
			(end -1.016 2.2352)
			(stroke
				(width 0.1524)
				(type default)
			)
			(layer "F.SilkS")
		)
		(fp_line
			(start 1.016 0.8382)
			(end 1.016 2.2352)
			(stroke
				(width 0.1524)
				(type default)
			)
			(layer "F.SilkS")
		)
		(fp_line
			(start -1.016 -0.8382)
			(end -1.016 -2.2352)
			(stroke
				(width 0.1524)
				(type default)
			)
			(layer "F.SilkS")
		)
		(fp_line
			(start -1.016 -2.2352)
			(end 1.016 -2.2352)
			(stroke
				(width 0.1524)
				(type default)
			)
			(layer "F.SilkS")
		)
		(fp_line
			(start 1.016 -2.2352)
			(end 1.016 -0.8382)
			(stroke
				(width 0.1524)
				(type default)
			)
			(layer "F.SilkS")
		)
		(fp_rect
			(start -1.0922 2.3114)
			(end 1.0922 -2.3114)
			(stroke
				(width 0)
				(type default)
			)
			(fill no)
			(layer "F.CrtYd")
		)
		(fp_poly
			(pts
				(xy 1.0922 -2.3114) (xy 1.0922 2.3114) (xy -1.0922 2.3114) (xy -1.0922 -2.3114)
			)
			(stroke
				(width 0)
				(type default)
			)
			(fill no)
			(layer "F.Fab")
		)
		(pad "1" smd rect
			(at 0 -1.397 270)
			(size 1.651 1.27)
			(layers "F.Cu" "F.Mask" "F.Paste")
			(net "P1V8_STBY")
		)
		(pad "2" smd rect
			(at 0 1.397 270)
			(size 1.651 1.27)
			(layers "F.Cu" "F.Mask" "F.Paste")
			(net "GND")
		)
	)
	(footprint ""
		(layer "F.Cu")
		(at 201.699876 -146.041872 90)
		(property "Reference" "SR763"
			(at 0 0 90)
			(layer "F.SilkS")
			(hide yes)
			(effects
				(font
					(size 1.27 1.27)
				)
			)
		)
		(property "Value" "4K7R2F-GP"
			(at 0.064008 -3.993896 90)
			(unlocked yes)
			(layer "F.Fab")
			(hide yes)
			(effects
				(font
					(size 1.016 1.016)
					(thickness 0.1524)
				)
			)
		)
		(property "Device Type" "R402H16"
			(at 0.064008 -5.517896 90)
			(unlocked yes)
			(layer "F.Fab")
			(hide yes)
			(effects
				(font
					(size 1.016 1.016)
					(thickness 0.1524)
				)
			)
		)
		(duplicate_pad_numbers_are_jumpers no)
		(fp_line
			(start 0.508 -0.9398)
			(end -0.508 -0.9398)
			(stroke
				(width 0.1524)
				(type default)
			)
			(layer "F.SilkS")
		)
		(fp_line
			(start -0.508 -0.9398)
			(end -0.508 0.9398)
			(stroke
				(width 0.1524)
				(type default)
			)
			(layer "F.SilkS")
		)
		(fp_rect
			(start -0.508 0.9398)
			(end 0.508 -0.9398)
			(stroke
				(width 0)
				(type default)
			)
			(fill no)
			(layer "F.CrtYd")
		)
		(fp_rect
			(start -0.508 0.9398)
			(end 0.508 -0.9398)
			(stroke
				(width 0)
				(type default)
			)
			(fill no)
			(layer "F.Fab")
		)
		(pad "1" smd custom
			(at 0 -0.4445 90)
			(size 0.1397 0.1397)
			(layers "F.Cu" "F.Mask" "F.Paste")
			(net "BMC_I2C_SCL_9")
			(options
				(clearance outline)
				(anchor circle)
			)
			(primitives
				(gr_poly
					(pts
						(arc
							(start -0.1778 -0.2794)
							(mid -0.249642 -0.249642)
							(end -0.2794 -0.1778)
						)
						(arc
							(start -0.2794 0.1778)
							(mid -0.249642 0.249642)
							(end -0.1778 0.2794)
						)
						(arc
							(start 0.1778 0.2794)
							(mid 0.249642 0.249642)
							(end 0.2794 0.1778)
						)
						(arc
							(start 0.2794 -0.1778)
							(mid 0.249642 -0.249642)
							(end 0.1778 -0.2794)
						)
					)
					(width 0)
					(fill yes)
				)
			)
		)
		(pad "2" smd custom
			(at 0 0.4445 90)
			(size 0.1397 0.1397)
			(layers "F.Cu" "F.Mask" "F.Paste")
			(net "P3V3_STBY")
			(options
				(clearance outline)
				(anchor circle)
			)
			(primitives
				(gr_poly
					(pts
						(arc
							(start -0.1778 -0.2794)
							(mid -0.249642 -0.249642)
							(end -0.2794 -0.1778)
						)
						(arc
							(start -0.2794 0.1778)
							(mid -0.249642 0.249642)
							(end -0.1778 0.2794)
						)
						(arc
							(start 0.1778 0.2794)
							(mid 0.249642 0.249642)
							(end 0.2794 0.1778)
						)
						(arc
							(start 0.2794 -0.1778)
							(mid 0.249642 -0.249642)
							(end 0.1778 -0.2794)
						)
					)
					(width 0)
					(fill yes)
				)
			)
		)
	)
	(footprint ""
		(layer "F.Cu")
		(at 285.1912 -191.77)
		(property "Reference" "C176"
			(at 0 0 0)
			(layer "F.SilkS")
			(hide yes)
			(effects
				(font
					(size 1.27 1.27)
				)
			)
		)
		(property "Value" "SCD1U16V2KX-3GP"
			(at 1.1811 -2.7051 0)
			(unlocked yes)
			(layer "F.Fab")
			(hide yes)
			(effects
				(font
					(size 1.016 1.016)
					(thickness 0.1524)
				)
			)
		)
		(property "Device Type" "C402H22"
			(at 1.1811 -4.2291 0)
			(unlocked yes)
			(layer "F.Fab")
			(hide yes)
			(effects
				(font
					(size 1.016 1.016)
					(thickness 0.1524)
				)
			)
		)
		(duplicate_pad_numbers_are_jumpers no)
		(fp_rect
			(start -0.4318 0.9525)
			(end 0.4318 -0.9525)
			(stroke
				(width 0)
				(type default)
			)
			(fill no)
			(layer "F.CrtYd")
		)
		(fp_rect
			(start -0.4318 0.9525)
			(end 0.4318 -0.9525)
			(stroke
				(width 0)
				(type default)
			)
			(fill no)
			(layer "F.Fab")
		)
		(pad "1" smd custom
			(at 0 -0.4445)
			(size 0.1524 0.1524)
			(layers "F.Cu" "F.Mask" "F.Paste")
			(net "P1V53_STBY")
			(options
				(clearance outline)
				(anchor circle)
			)
			(primitives
				(gr_poly
					(pts
						(arc
							(start 0.3048 -0.2032)
							(mid 0.275042 -0.275042)
							(end 0.2032 -0.3048)
						)
						(arc
							(start -0.2032 -0.3048)
							(mid -0.275042 -0.275042)
							(end -0.3048 -0.2032)
						)
						(arc
							(start -0.3048 0.2032)
							(mid -0.275042 0.275042)
							(end -0.2032 0.3048)
						)
						(arc
							(start 0.2032 0.3048)
							(mid 0.275042 0.275042)
							(end 0.3048 0.2032)
						)
					)
					(width 0)
					(fill yes)
				)
			)
		)
		(pad "2" smd custom
			(at 0 0.4445)
			(size 0.1524 0.1524)
			(layers "F.Cu" "F.Mask" "F.Paste")
			(net "GND")
			(options
				(clearance outline)
				(anchor circle)
			)
			(primitives
				(gr_poly
					(pts
						(arc
							(start 0.3048 -0.2032)
							(mid 0.275042 -0.275042)
							(end 0.2032 -0.3048)
						)
						(arc
							(start -0.2032 -0.3048)
							(mid -0.275042 -0.275042)
							(end -0.3048 -0.2032)
						)
						(arc
							(start -0.3048 0.2032)
							(mid -0.275042 0.275042)
							(end -0.2032 0.3048)
						)
						(arc
							(start 0.2032 0.3048)
							(mid 0.275042 0.275042)
							(end 0.3048 0.2032)
						)
					)
					(width 0)
					(fill yes)
				)
			)
		)
	)
	(footprint ""
		(layer "F.Cu")
		(at 307.721 -219.837 180)
		(property "Reference" "U44"
			(at 0 0 180)
			(layer "F.SilkS")
			(hide yes)
			(effects
				(font
					(size 1.27 1.27)
				)
			)
		)
		(property "Value" "SN74LVC1G00DC-1GP"
			(at -2.3368 -8.6868 180)
			(unlocked yes)
			(layer "F.Fab")
			(hide yes)
			(effects
				(font
					(size 1.016 1.016)
					(thickness 0.1524)
				)
			)
		)
		(property "Device Type" "SC70-5H44"
			(at -2.3114 -10.414 180)
			(unlocked yes)
			(layer "F.Fab")
			(hide yes)
			(effects
				(font
					(size 1.016 1.016)
					(thickness 0.1524)
				)
			)
		)
		(duplicate_pad_numbers_are_jumpers no)
		(fp_line
			(start 1.3843 -1.8034)
			(end 1.3843 -1.1176)
			(stroke
				(width 0.3302)
				(type default)
			)
			(layer "F.SilkS")
		)
		(fp_line
			(start 1.27 1.7018)
			(end -1.27 1.7018)
			(stroke
				(width 0.1524)
				(type default)
			)
			(layer "F.SilkS")
		)
		(fp_line
			(start 1.27 -1.7018)
			(end 1.27 1.7018)
			(stroke
				(width 0.1524)
				(type default)
			)
			(layer "F.SilkS")
		)
		(fp_line
			(start 0.6604 -1.8034)
			(end 1.3843 -1.8034)
			(stroke
				(width 0.3302)
				(type default)
			)
			(layer "F.SilkS")
		)
		(fp_line
			(start -1.27 1.7018)
			(end -1.27 -1.7018)
			(stroke
				(width 0.1524)
				(type default)
			)
			(layer "F.SilkS")
		)
		(fp_line
			(start -1.27 -1.7018)
			(end 1.27 -1.7018)
			(stroke
				(width 0.1524)
				(type default)
			)
			(layer "F.SilkS")
		)
		(fp_rect
			(start -1.524 1.9558)
			(end 1.524 -1.9558)
			(stroke
				(width 0)
				(type default)
			)
			(fill no)
			(layer "F.CrtYd")
		)
		(fp_poly
			(pts
				(xy -1.524 -1.9558) (xy 1.524 -1.9558) (xy 1.524 1.9558) (xy -1.524 1.9558)
			)
			(stroke
				(width 0)
				(type default)
			)
			(fill no)
			(layer "F.Fab")
		)
		(pad "1" smd rect
			(at 0.65024 -0.8255 180)
			(size 0.4064 1.2192)
			(layers "F.Cu" "F.Mask" "F.Paste")
			(net "PMU_PLTRST_N")
		)
		(pad "2" smd rect
			(at 0 -0.8255 180)
			(size 0.4064 1.2192)
			(layers "F.Cu" "F.Mask" "F.Paste")
			(net "BMC_DEBUG_OE_2_N")
		)
		(pad "3" smd rect
			(at -0.65024 -0.8255 180)
			(size 0.4064 1.2192)
			(layers "F.Cu" "F.Mask" "F.Paste")
			(net "GND")
		)
		(pad "4" smd rect
			(at -0.65024 0.8255 180)
			(size 0.4064 1.2192)
			(layers "F.Cu" "F.Mask" "F.Paste")
			(net "DEBUG_OE_2_N")
		)
		(pad "5" smd rect
			(at 0.65024 0.8255 180)
			(size 0.4064 1.2192)
			(layers "F.Cu" "F.Mask" "F.Paste")
			(net "P3V3_STBY")
		)
	)
	(footprint ""
		(layer "F.Cu")
		(at 11.126216 -237.29188 180)
		(property "Reference" "SC431"
			(at 0 0 180)
			(layer "F.SilkS")
			(hide yes)
			(effects
				(font
					(size 1.27 1.27)
				)
			)
		)
		(property "Value" "SCD1U16V2KX-3GP"
			(at 1.1811 -2.7051 180)
			(unlocked yes)
			(layer "F.Fab")
			(hide yes)
			(effects
				(font
					(size 1.016 1.016)
					(thickness 0.1524)
				)
			)
		)
		(property "Device Type" "C402H22"
			(at 1.1811 -4.2291 180)
			(unlocked yes)
			(layer "F.Fab")
			(hide yes)
			(effects
				(font
					(size 1.016 1.016)
					(thickness 0.1524)
				)
			)
		)
		(duplicate_pad_numbers_are_jumpers no)
		(fp_rect
			(start -0.4318 0.9525)
			(end 0.4318 -0.9525)
			(stroke
				(width 0)
				(type default)
			)
			(fill no)
			(layer "F.CrtYd")
		)
		(fp_rect
			(start -0.4318 0.9525)
			(end 0.4318 -0.9525)
			(stroke
				(width 0)
				(type default)
			)
			(fill no)
			(layer "F.Fab")
		)
		(pad "1" smd custom
			(at 0 -0.4445 180)
			(size 0.1524 0.1524)
			(layers "F.Cu" "F.Mask" "F.Paste")
			(net "P3V3_STBY")
			(options
				(clearance outline)
				(anchor circle)
			)
			(primitives
				(gr_poly
					(pts
						(arc
							(start 0.3048 -0.2032)
							(mid 0.275042 -0.275042)
							(end 0.2032 -0.3048)
						)
						(arc
							(start -0.2032 -0.3048)
							(mid -0.275042 -0.275042)
							(end -0.3048 -0.2032)
						)
						(arc
							(start -0.3048 0.2032)
							(mid -0.275042 0.275042)
							(end -0.2032 0.3048)
						)
						(arc
							(start 0.2032 0.3048)
							(mid 0.275042 0.275042)
							(end 0.3048 0.2032)
						)
					)
					(width 0)
					(fill yes)
				)
			)
		)
		(pad "2" smd custom
			(at 0 0.4445 180)
			(size 0.1524 0.1524)
			(layers "F.Cu" "F.Mask" "F.Paste")
			(net "GND")
			(options
				(clearance outline)
				(anchor circle)
			)
			(primitives
				(gr_poly
					(pts
						(arc
							(start 0.3048 -0.2032)
							(mid 0.275042 -0.275042)
							(end 0.2032 -0.3048)
						)
						(arc
							(start -0.2032 -0.3048)
							(mid -0.275042 -0.275042)
							(end -0.3048 -0.2032)
						)
						(arc
							(start -0.3048 0.2032)
							(mid -0.275042 0.275042)
							(end -0.2032 0.3048)
						)
						(arc
							(start 0.2032 0.3048)
							(mid 0.275042 0.275042)
							(end 0.3048 0.2032)
						)
					)
					(width 0)
					(fill yes)
				)
			)
		)
	)
)
